# BASEBOARD_FAB2 (Tioga Pass) — schematic netlist excerpt (pin names and nets, part order shuffled) for the footprints in the layout excerpt that follows; sources: Cadence DE-HDL packaged netlist, KiCad conversion of Wiwynn_Tioga_Pass_MB.brd

R1R21  RES  2.21K 1% CHIP  pkg 0402  page 188 : A = P3V3_STBY ; B = SMB_PCH_MEZZ_LOM1_SDA
C3N40  CAP_A  1.0UF 6.3V 10% X6S  pkg 0402V  page 194 : A = PVCCIOMCP_CPU0 ; B = GND

(kicad_pcb
	(version 20260206)
	(generator "pcbnew")
	(generator_version "10.0")
	(general
		(thickness 1.6)
		(legacy_teardrops no)
	)
	(paper "A4")
	(title_block
		(title "Wiwynn_Tioga_Pass_MB.brd")
		(comment 1 "Tioga Pass / footprints 4444-4445 of 4770")
	)
	(layers
		(0 "F.Cu" signal "TOP")
		(4 "In1.Cu" signal "L2GND")
		(6 "In2.Cu" signal "L3")
		(8 "In3.Cu" signal "L4GND")
		(10 "In4.Cu" signal "L5")
		(12 "In5.Cu" signal "L6GND")
		(14 "In6.Cu" signal "L7VCC")
		(16 "In7.Cu" signal "L8VCC")
		(18 "In8.Cu" signal "L9GND")
		(20 "In9.Cu" signal "L10")
		(22 "In10.Cu" signal "L11GND")
		(24 "In11.Cu" signal "L12")
		(26 "In12.Cu" signal "L13GND")
		(2 "B.Cu" signal "BOTTOM")
		(9 "F.Adhes" user "F.Adhesive")
		(11 "B.Adhes" user "B.Adhesive")
		(13 "F.Paste" user "Package Geometry/Pastemask Top")
		(15 "B.Paste" user "Package Geometry/Pastemask Bottom")
		(5 "F.SilkS" user "Ref Des/Silkscreen Top")
		(7 "B.SilkS" user "Ref Des/Silkscreen Bottom")
		(1 "F.Mask" user "Board Geometry/Soldermask Top")
		(3 "B.Mask" user "Board Geometry/Soldermask Bottom")
		(17 "Dwgs.User" user "User.Drawings")
		(19 "Cmts.User" user "User.Comments")
		(21 "Eco1.User" user "User.Eco1")
		(23 "Eco2.User" user "User.Eco2")
		(25 "Edge.Cuts" user "Board Geometry/Outline")
		(27 "Margin" user)
		(31 "F.CrtYd" user "Package Geometry/Place Bound Top")
		(29 "B.CrtYd" user "Package Geometry/Place Bound Bottom")
		(35 "F.Fab" user "Ref Des/Assembly Top")
		(33 "B.Fab" user "Ref Des/Assembly Bottom")
	)
	(footprint ""
		(layer "B.Cu")
		(at 352.425 -108.4834)
		(property "Reference" "C3N40"
			(at 0 0 0)
			(layer "B.SilkS")
			(hide yes)
			(effects
				(font
					(size 1.27 1.27)
				)
				(justify mirror)
			)
		)
		(property "Value" ""
			(at 0 0 0)
			(layer "B.Fab")
			(effects
				(font
					(size 1.27 1.27)
				)
				(justify mirror)
			)
		)
		(duplicate_pad_numbers_are_jumpers no)
		(fp_poly
			(pts
				(xy -0.3048 -0.1016) (xy -0.3048 0.9906) (xy 0.3048 0.9906) (xy 0.3048 -0.1016)
			)
			(stroke
				(width 0)
				(type default)
			)
			(fill no)
			(layer "B.CrtYd")
		)
		(fp_line
			(start -0.3048 -0.1016)
			(end 0.3048 -0.1016)
			(stroke
				(width 0.1)
				(type default)
			)
			(layer "B.Fab")
		)
		(fp_line
			(start -0.3048 0.9906)
			(end -0.3048 -0.1016)
			(stroke
				(width 0.1)
				(type default)
			)
			(layer "B.Fab")
		)
		(fp_line
			(start 0.3048 -0.1016)
			(end 0.3048 0.9906)
			(stroke
				(width 0.1)
				(type default)
			)
			(layer "B.Fab")
		)
		(fp_line
			(start 0.3048 0.9906)
			(end -0.3048 0.9906)
			(stroke
				(width 0.1)
				(type default)
			)
			(layer "B.Fab")
		)
		(pad "1" smd rect
			(at 0 0 180)
			(size 0.508 0.508)
			(layers "B.Cu" "B.Mask" "B.Paste")
			(net "PVCCIOMCP_CPU0")
		)
		(pad "2" smd rect
			(at 0 0.889 180)
			(size 0.508 0.508)
			(layers "B.Cu" "B.Mask" "B.Paste")
			(net "GND")
		)
		(zone
			(layer "B.Cu")
			(hatch none 0.5)
			(connect_pads
				(clearance 0)
			)
			(min_thickness 0.25)
			(keepout
				(tracks allowed)
				(vias not_allowed)
				(pads allowed)
				(copperpour not_allowed)
				(footprints allowed)
			)
			(placement
				(enabled no)
				(sheetname "")
			)
			(fill
				(thermal_gap 0.5)
				(thermal_bridge_width 0.5)
				(island_removal_mode 0)
			)
			(polygon
				(pts
					(xy 352.679 -108.2294) (xy 352.171 -108.2294) (xy 352.171 -107.8484) (xy 352.679 -107.8484)
				)
			)
		)
		(zone
			(layer "B.Cu")
			(hatch none 0.5)
			(connect_pads
				(clearance 0)
			)
			(min_thickness 0.25)
			(keepout
				(tracks not_allowed)
				(vias allowed)
				(pads allowed)
				(copperpour not_allowed)
				(footprints allowed)
			)
			(placement
				(enabled no)
				(sheetname "")
			)
			(fill
				(thermal_gap 0.5)
				(thermal_bridge_width 0.5)
				(island_removal_mode 0)
			)
			(polygon
				(pts
					(xy 352.679 -107.8484) (xy 352.171 -107.8484) (xy 352.171 -108.2294) (xy 352.679 -108.2294)
				)
			)
		)
	)
	(footprint ""
		(layer "B.Cu")
		(at 470.027 -57.15 -90)
		(property "Reference" "R1R21"
			(at 0 0 90)
			(layer "B.SilkS")
			(hide yes)
			(effects
				(font
					(size 1.27 1.27)
				)
				(justify mirror)
			)
		)
		(property "Value" ""
			(at 0 0 90)
			(layer "B.Fab")
			(effects
				(font
					(size 1.27 1.27)
				)
				(justify mirror)
			)
		)
		(duplicate_pad_numbers_are_jumpers no)
		(fp_poly
			(pts
				(xy 0.2794 -0.1016) (xy -0.2794 -0.1016) (xy -0.2794 0.9906) (xy 0.2794 0.9906)
			)
			(stroke
				(width 0)
				(type default)
			)
			(fill no)
			(layer "B.CrtYd")
		)
		(fp_line
			(start -0.2794 0.9906)
			(end -0.2794 -0.1016)
			(stroke
				(width 0.1)
				(type default)
			)
			(layer "B.Fab")
		)
		(fp_line
			(start 0.2794 0.9906)
			(end -0.2794 0.9906)
			(stroke
				(width 0.1)
				(type default)
			)
			(layer "B.Fab")
		)
		(fp_line
			(start -0.2794 -0.1016)
			(end 0.2794 -0.1016)
			(stroke
				(width 0.1)
				(type default)
			)
			(layer "B.Fab")
		)
		(fp_line
			(start 0.2794 -0.1016)
			(end 0.2794 0.9906)
			(stroke
				(width 0.1)
				(type default)
			)
			(layer "B.Fab")
		)
		(pad "1" smd rect
			(at 0 0 90)
			(size 0.508 0.508)
			(layers "B.Cu" "B.Mask" "B.Paste")
			(net "P3V3_STBY")
		)
		(pad "2" smd rect
			(at 0 0.889 90)
			(size 0.508 0.508)
			(layers "B.Cu" "B.Mask" "B.Paste")
			(net "SMB_PCH_MEZZ_LOM1_SDA")
		)
		(zone
			(layer "B.Cu")
			(hatch none 0.5)
			(connect_pads
				(clearance 0)
			)
			(min_thickness 0.25)
			(keepout
				(tracks not_allowed)
				(vias allowed)
				(pads allowed)
				(copperpour not_allowed)
				(footprints allowed)
			)
			(placement
				(enabled no)
				(sheetname "")
			)
			(fill
				(thermal_gap 0.5)
				(thermal_bridge_width 0.5)
				(island_removal_mode 0)
			)
			(polygon
				(pts
					(xy 469.392 -56.896) (xy 469.392 -57.404) (xy 469.773 -57.404) (xy 469.773 -56.896)
				)
			)
		)
		(zone
			(layer "B.Cu")
			(hatch none 0.5)
			(connect_pads
				(clearance 0)
			)
			(min_thickness 0.25)
			(keepout
				(tracks allowed)
				(vias not_allowed)
				(pads allowed)
				(copperpour not_allowed)
				(footprints allowed)
			)
			(placement
				(enabled no)
				(sheetname "")
			)
			(fill
				(thermal_gap 0.5)
				(thermal_bridge_width 0.5)
				(island_removal_mode 0)
			)
			(polygon
				(pts
					(xy 469.773 -56.896) (xy 469.773 -57.404) (xy 469.392 -57.404) (xy 469.392 -56.896)
				)
			)
		)
	)
)
